(kicad_pcb
	(version 20260206)
	(generator "pcbnew")
	(generator_version "10.0")
	(general
		(thickness 1.6)
		(legacy_teardrops no)
	)
	(paper "A4")
	(title_block
		(title "Bryce Canyon_F.DPB_16315-1-OCP.brd")
		(comment 1 "Bryce Canyon / footprints 1564-1570 of 2223")
	)
	(layers
		(0 "F.Cu" signal "TOP")
		(4 "In1.Cu" signal "L2GND")
		(6 "In2.Cu" signal "L3")
		(8 "In3.Cu" signal "L4GND")
		(10 "In4.Cu" signal "L5")
		(12 "In5.Cu" signal "L6VCC")
		(14 "In6.Cu" signal "L7VCC")
		(16 "In7.Cu" signal "L8")
		(18 "In8.Cu" signal "L9GND")
		(20 "In9.Cu" signal "L10")
		(22 "In10.Cu" signal "L11GND")
		(2 "B.Cu" signal "BOTTOM")
		(9 "F.Adhes" user "F.Adhesive")
		(11 "B.Adhes" user "B.Adhesive")
		(13 "F.Paste" user "Package Geometry/Pastemask Top")
		(15 "B.Paste" user "Package Geometry/Pastemask Bottom")
		(5 "F.SilkS" user "Ref Des/Silkscreen Top")
		(7 "B.SilkS" user "Ref Des/Silkscreen Bottom")
		(1 "F.Mask" user "Board Geometry/Soldermask Top")
		(3 "B.Mask" user "Board Geometry/Soldermask Bottom")
		(17 "Dwgs.User" user "User.Drawings")
		(19 "Cmts.User" user "User.Comments")
		(21 "Eco1.User" user "User.Eco1")
		(23 "Eco2.User" user "User.Eco2")
		(25 "Edge.Cuts" user "Board Geometry/Outline")
		(27 "Margin" user)
		(31 "F.CrtYd" user "Package Geometry/Place Bound Top")
		(29 "B.CrtYd" user "Package Geometry/Place Bound Bottom")
		(35 "F.Fab" user "Ref Des/Assembly Top")
		(33 "B.Fab" user "Ref Des/Assembly Bottom")
	)
	(footprint ""
		(layer "F.Cu")
		(at 115.080796 -163.554918 180)
		(property "Reference" "Q91"
			(at 0 0 180)
			(layer "F.SilkS")
			(hide yes)
			(effects
				(font
					(size 1.27 1.27)
				)
			)
		)
		(property "Value" "2N7002KDW-GP"
			(at -2.3622 -8.2042 180)
			(unlocked yes)
			(layer "F.Fab")
			(hide yes)
			(effects
				(font
					(size 1.016 1.016)
					(thickness 0.1524)
				)
			)
		)
		(property "Device Type" "SOT-363H44"
			(at -2.3622 -10.1092 180)
			(unlocked yes)
			(layer "F.Fab")
			(hide yes)
			(effects
				(font
					(size 1.016 1.016)
					(thickness 0.1524)
				)
			)
		)
		(duplicate_pad_numbers_are_jumpers no)
		(fp_line
			(start 1.4478 1.7018)
			(end 1.4478 -1.7018)
			(stroke
				(width 0.1524)
				(type default)
			)
			(layer "F.SilkS")
		)
		(fp_line
			(start 1.4478 -1.7018)
			(end -1.4478 -1.7018)
			(stroke
				(width 0.1524)
				(type default)
			)
			(layer "F.SilkS")
		)
		(fp_line
			(start -1.27 1.524)
			(end -1.27 0.6604)
			(stroke
				(width 0.4826)
				(type default)
			)
			(layer "F.SilkS")
		)
		(fp_line
			(start -1.4478 1.7018)
			(end 1.4478 1.7018)
			(stroke
				(width 0.1524)
				(type default)
			)
			(layer "F.SilkS")
		)
		(fp_line
			(start -1.4478 -1.7018)
			(end -1.4478 1.7018)
			(stroke
				(width 0.1524)
				(type default)
			)
			(layer "F.SilkS")
		)
		(fp_poly
			(pts
				(xy -1.524 -1.778) (xy 1.524 -1.778) (xy 1.524 1.778) (xy -1.524 1.778)
			)
			(stroke
				(width 0)
				(type default)
			)
			(fill no)
			(layer "F.CrtYd")
		)
		(fp_poly
			(pts
				(xy -1.524 -1.778) (xy 1.524 -1.778) (xy 1.524 1.778) (xy -1.524 1.778)
			)
			(stroke
				(width 0)
				(type default)
			)
			(fill no)
			(layer "F.Fab")
		)
		(pad "1" smd rect
			(at -0.65024 0.9398 180)
			(size 0.4064 1.016)
			(layers "F.Cu" "F.Mask" "F.Paste")
			(net "GND")
		)
		(pad "2" smd rect
			(at 0 0.9398 180)
			(size 0.4064 1.016)
			(layers "F.Cu" "F.Mask" "F.Paste")
			(net "SW_PWR_R_HDD15")
		)
		(pad "3" smd rect
			(at 0.65024 0.9398 180)
			(size 0.4064 1.016)
			(layers "F.Cu" "F.Mask" "F.Paste")
			(net "SW_HDD_P15")
		)
		(pad "4" smd rect
			(at 0.65024 -0.9398 180)
			(size 0.4064 1.016)
			(layers "F.Cu" "F.Mask" "F.Paste")
			(net "GND")
		)
		(pad "5" smd rect
			(at 0 -0.9398 180)
			(size 0.4064 1.016)
			(layers "F.Cu" "F.Mask" "F.Paste")
			(net "SW_HDD_G15")
		)
		(pad "6" smd rect
			(at -0.65024 -0.9398 180)
			(size 0.4064 1.016)
			(layers "F.Cu" "F.Mask" "F.Paste")
			(net "SW_HDD_R15")
		)
	)
	(footprint ""
		(layer "F.Cu")
		(at 346.005912 -137.746994 90)
		(property "Reference" "R1102"
			(at 0 0 90)
			(layer "F.SilkS")
			(hide yes)
			(effects
				(font
					(size 1.27 1.27)
				)
			)
		)
		(property "Value" "1KR2F-3-GP"
			(at 0.064008 -3.993896 90)
			(unlocked yes)
			(layer "F.Fab")
			(hide yes)
			(effects
				(font
					(size 1.016 1.016)
					(thickness 0.1524)
				)
			)
		)
		(property "Device Type" "R402H16"
			(at 0.064008 -5.517896 90)
			(unlocked yes)
			(layer "F.Fab")
			(hide yes)
			(effects
				(font
					(size 1.016 1.016)
					(thickness 0.1524)
				)
			)
		)
		(duplicate_pad_numbers_are_jumpers no)
		(fp_line
			(start 0.508 -0.9398)
			(end -0.508 -0.9398)
			(stroke
				(width 0.1524)
				(type default)
			)
			(layer "F.SilkS")
		)
		(fp_line
			(start -0.508 -0.9398)
			(end -0.508 0.9398)
			(stroke
				(width 0.1524)
				(type default)
			)
			(layer "F.SilkS")
		)
		(fp_rect
			(start -0.508 0.9398)
			(end 0.508 -0.9398)
			(stroke
				(width 0)
				(type default)
			)
			(fill no)
			(layer "F.CrtYd")
		)
		(fp_rect
			(start -0.508 0.9398)
			(end 0.508 -0.9398)
			(stroke
				(width 0)
				(type default)
			)
			(fill no)
			(layer "F.Fab")
		)
		(pad "1" smd custom
			(at 0 -0.4445 90)
			(size 0.1397 0.1397)
			(layers "F.Cu" "F.Mask" "F.Paste")
			(net "MB1_CM_VOUT_R")
			(options
				(clearance outline)
				(anchor circle)
			)
			(primitives
				(gr_poly
					(pts
						(arc
							(start -0.1778 -0.2794)
							(mid -0.249642 -0.249642)
							(end -0.2794 -0.1778)
						)
						(arc
							(start -0.2794 0.1778)
							(mid -0.249642 0.249642)
							(end -0.1778 0.2794)
						)
						(arc
							(start 0.1778 0.2794)
							(mid 0.249642 0.249642)
							(end 0.2794 0.1778)
						)
						(arc
							(start 0.2794 -0.1778)
							(mid 0.249642 -0.249642)
							(end 0.1778 -0.2794)
						)
					)
					(width 0)
					(fill yes)
				)
			)
		)
		(pad "2" smd custom
			(at 0 0.4445 90)
			(size 0.1397 0.1397)
			(layers "F.Cu" "F.Mask" "F.Paste")
			(net "P12V_B_COMP")
			(options
				(clearance outline)
				(anchor circle)
			)
			(primitives
				(gr_poly
					(pts
						(arc
							(start -0.1778 -0.2794)
							(mid -0.249642 -0.249642)
							(end -0.2794 -0.1778)
						)
						(arc
							(start -0.2794 0.1778)
							(mid -0.249642 0.249642)
							(end -0.1778 0.2794)
						)
						(arc
							(start 0.1778 0.2794)
							(mid 0.249642 0.249642)
							(end 0.2794 0.1778)
						)
						(arc
							(start 0.2794 -0.1778)
							(mid 0.249642 -0.249642)
							(end 0.1778 -0.2794)
						)
					)
					(width 0)
					(fill yes)
				)
			)
		)
	)
	(footprint ""
		(layer "F.Cu")
		(at 224.028 -365.125 180)
		(property "Reference" "R171"
			(at 0 0 180)
			(layer "F.SilkS")
			(hide yes)
			(effects
				(font
					(size 1.27 1.27)
				)
			)
		)
		(property "Value" "4K7R2F-GP"
			(at 0.064008 -3.993896 180)
			(unlocked yes)
			(layer "F.Fab")
			(hide yes)
			(effects
				(font
					(size 1.016 1.016)
					(thickness 0.1524)
				)
			)
		)
		(property "Device Type" "R402H16"
			(at 0.064008 -5.517896 180)
			(unlocked yes)
			(layer "F.Fab")
			(hide yes)
			(effects
				(font
					(size 1.016 1.016)
					(thickness 0.1524)
				)
			)
		)
		(duplicate_pad_numbers_are_jumpers no)
		(fp_line
			(start 0.508 -0.9398)
			(end -0.508 -0.9398)
			(stroke
				(width 0.1524)
				(type default)
			)
			(layer "F.SilkS")
		)
		(fp_line
			(start -0.508 -0.9398)
			(end -0.508 0.9398)
			(stroke
				(width 0.1524)
				(type default)
			)
			(layer "F.SilkS")
		)
		(fp_rect
			(start -0.508 0.9398)
			(end 0.508 -0.9398)
			(stroke
				(width 0)
				(type default)
			)
			(fill no)
			(layer "F.CrtYd")
		)
		(fp_rect
			(start -0.508 0.9398)
			(end 0.508 -0.9398)
			(stroke
				(width 0)
				(type default)
			)
			(fill no)
			(layer "F.Fab")
		)
		(pad "1" smd custom
			(at 0 -0.4445 180)
			(size 0.1397 0.1397)
			(layers "F.Cu" "F.Mask" "F.Paste")
			(net "P3V3_STBY_B")
			(options
				(clearance outline)
				(anchor circle)
			)
			(primitives
				(gr_poly
					(pts
						(arc
							(start -0.1778 -0.2794)
							(mid -0.249642 -0.249642)
							(end -0.2794 -0.1778)
						)
						(arc
							(start -0.2794 0.1778)
							(mid -0.249642 0.249642)
							(end -0.1778 0.2794)
						)
						(arc
							(start 0.1778 0.2794)
							(mid 0.249642 0.249642)
							(end 0.2794 0.1778)
						)
						(arc
							(start 0.2794 -0.1778)
							(mid 0.249642 -0.249642)
							(end 0.1778 -0.2794)
						)
					)
					(width 0)
					(fill yes)
				)
			)
		)
		(pad "2" smd custom
			(at 0 0.4445 180)
			(size 0.1397 0.1397)
			(layers "F.Cu" "F.Mask" "F.Paste")
			(net "IO_EXP3_HDD_FAULT_A2")
			(options
				(clearance outline)
				(anchor circle)
			)
			(primitives
				(gr_poly
					(pts
						(arc
							(start -0.1778 -0.2794)
							(mid -0.249642 -0.249642)
							(end -0.2794 -0.1778)
						)
						(arc
							(start -0.2794 0.1778)
							(mid -0.249642 0.249642)
							(end -0.1778 0.2794)
						)
						(arc
							(start 0.1778 0.2794)
							(mid 0.249642 0.249642)
							(end 0.2794 0.1778)
						)
						(arc
							(start 0.2794 -0.1778)
							(mid 0.249642 -0.249642)
							(end 0.1778 -0.2794)
						)
					)
					(width 0)
					(fill yes)
				)
			)
		)
	)
	(footprint ""
		(layer "F.Cu")
		(at 132.675884 -185.106564)
		(property "Reference" "Q267"
			(at 0 0 0)
			(layer "F.SilkS")
			(hide yes)
			(effects
				(font
					(size 1.27 1.27)
				)
			)
		)
		(property "Value" "SSM3K324R-GP"
			(at 0.127 -8.9662 0)
			(unlocked yes)
			(layer "F.Fab")
			(hide yes)
			(effects
				(font
					(size 1.016 1.016)
					(thickness 0.1524)
				)
			)
		)
		(property "Device Type" "SOT23DGS2D4H35"
			(at 0.127 -10.4902 0)
			(unlocked yes)
			(layer "F.Fab")
			(hide yes)
			(effects
				(font
					(size 1.016 1.016)
					(thickness 0.1524)
				)
			)
		)
		(duplicate_pad_numbers_are_jumpers no)
		(fp_line
			(start -1.651 -1.778)
			(end -1.651 1.778)
			(stroke
				(width 0.1524)
				(type default)
			)
			(layer "F.SilkS")
		)
		(fp_line
			(start -1.651 1.778)
			(end 1.651 1.778)
			(stroke
				(width 0.1524)
				(type default)
			)
			(layer "F.SilkS")
		)
		(fp_line
			(start 1.651 -1.778)
			(end -1.651 -1.778)
			(stroke
				(width 0.1524)
				(type default)
			)
			(layer "F.SilkS")
		)
		(fp_line
			(start 1.651 1.778)
			(end 1.651 -1.778)
			(stroke
				(width 0.1524)
				(type default)
			)
			(layer "F.SilkS")
		)
		(fp_poly
			(pts
				(xy -1.778 1.8796) (xy -1.778 -1.8796) (xy 1.778 -1.8796) (xy 1.778 1.8796)
			)
			(stroke
				(width 0)
				(type default)
			)
			(fill no)
			(layer "F.CrtYd")
		)
		(fp_poly
			(pts
				(xy -1.778 1.8796) (xy -1.778 -1.8796) (xy 1.778 -1.8796) (xy 1.778 1.8796)
			)
			(stroke
				(width 0)
				(type default)
			)
			(fill no)
			(layer "F.Fab")
		)
		(pad "D" smd custom
			(at 0 -0.9525)
			(size 0.1905 0.1905)
			(layers "F.Cu" "F.Mask" "F.Paste")
			(net "DRV_ACT_4_N")
			(options
				(clearance outline)
				(anchor circle)
			)
			(primitives
				(gr_poly
					(pts
						(arc
							(start -0.1778 0.5715)
							(mid -0.321484 0.511984)
							(end -0.381 0.3683)
						)
						(arc
							(start -0.381 -0.3683)
							(mid -0.321484 -0.511984)
							(end -0.1778 -0.5715)
						)
						(arc
							(start 0.1778 -0.5715)
							(mid 0.321484 -0.511984)
							(end 0.381 -0.3683)
						)
						(arc
							(start 0.381 0.3683)
							(mid 0.321484 0.511984)
							(end 0.1778 0.5715)
						)
					)
					(width 0)
					(fill yes)
				)
			)
		)
		(pad "G" smd custom
			(at -0.98425 0.9525)
			(size 0.1905 0.1905)
			(layers "F.Cu" "F.Mask" "F.Paste")
			(net "DRIVE_A_4_ACT")
			(options
				(clearance outline)
				(anchor circle)
			)
			(primitives
				(gr_poly
					(pts
						(arc
							(start -0.1778 0.5715)
							(mid -0.321484 0.511984)
							(end -0.381 0.3683)
						)
						(arc
							(start -0.381 -0.3683)
							(mid -0.321484 -0.511984)
							(end -0.1778 -0.5715)
						)
						(arc
							(start 0.1778 -0.5715)
							(mid 0.321484 -0.511984)
							(end 0.381 -0.3683)
						)
						(arc
							(start 0.381 0.3683)
							(mid 0.321484 0.511984)
							(end 0.1778 0.5715)
						)
					)
					(width 0)
					(fill yes)
				)
			)
		)
		(pad "S" smd custom
			(at 0.98425 0.9525)
			(size 0.1905 0.1905)
			(layers "F.Cu" "F.Mask" "F.Paste")
			(net "GND")
			(options
				(clearance outline)
				(anchor circle)
			)
			(primitives
				(gr_poly
					(pts
						(arc
							(start -0.1778 0.5715)
							(mid -0.321484 0.511984)
							(end -0.381 0.3683)
						)
						(arc
							(start -0.381 -0.3683)
							(mid -0.321484 -0.511984)
							(end -0.1778 -0.5715)
						)
						(arc
							(start 0.1778 -0.5715)
							(mid 0.321484 -0.511984)
							(end 0.381 -0.3683)
						)
						(arc
							(start 0.381 0.3683)
							(mid 0.321484 0.511984)
							(end 0.1778 0.5715)
						)
					)
					(width 0)
					(fill yes)
				)
			)
		)
	)
	(footprint ""
		(layer "F.Cu")
		(at 457.6699 -61.127894 -90)
		(property "Reference" "R911"
			(at 0 0 270)
			(layer "F.SilkS")
			(hide yes)
			(effects
				(font
					(size 1.27 1.27)
				)
			)
		)
		(property "Value" "2R6F-GP"
			(at -0.0508 -4.8514 270)
			(unlocked yes)
			(layer "F.Fab")
			(hide yes)
			(effects
				(font
					(size 1.016 1.016)
					(thickness 0.1524)
				)
			)
		)
		(property "Device Type" "R1206H26"
			(at 0 -6.3754 270)
			(unlocked yes)
			(layer "F.Fab")
			(hide yes)
			(effects
				(font
					(size 1.016 1.016)
					(thickness 0.1524)
				)
			)
		)
		(duplicate_pad_numbers_are_jumpers no)
		(fp_line
			(start -1.016 2.2352)
			(end -1.016 -2.2352)
			(stroke
				(width 0.1524)
				(type default)
			)
			(layer "F.SilkS")
		)
		(fp_line
			(start 1.016 2.2352)
			(end -1.016 2.2352)
			(stroke
				(width 0.1524)
				(type default)
			)
			(layer "F.SilkS")
		)
		(fp_line
			(start -1.016 -2.2352)
			(end 1.016 -2.2352)
			(stroke
				(width 0.1524)
				(type default)
			)
			(layer "F.SilkS")
		)
		(fp_line
			(start 1.016 -2.2352)
			(end 1.016 2.2352)
			(stroke
				(width 0.1524)
				(type default)
			)
			(layer "F.SilkS")
		)
		(fp_rect
			(start -1.0922 2.3114)
			(end 1.0922 -2.3114)
			(stroke
				(width 0)
				(type default)
			)
			(fill no)
			(layer "F.CrtYd")
		)
		(fp_poly
			(pts
				(xy -1.0922 -2.3114) (xy 1.0922 -2.3114) (xy 1.0922 2.3114) (xy -1.0922 2.3114)
			)
			(stroke
				(width 0)
				(type default)
			)
			(fill no)
			(layer "F.Fab")
		)
		(pad "1" smd rect
			(at 0 -1.397 270)
			(size 1.651 1.27)
			(layers "F.Cu" "F.Mask" "F.Paste")
			(net "P5V_HDD34")
		)
		(pad "2" smd rect
			(at 0 1.397 270)
			(size 1.651 1.27)
			(layers "F.Cu" "F.Mask" "F.Paste")
			(net "5V_PRE_34")
		)
	)
	(footprint ""
		(layer "F.Cu")
		(at 235.331 -382.1938)
		(property "Reference" "R1159"
			(at 0 0 0)
			(layer "F.SilkS")
			(hide yes)
			(effects
				(font
					(size 1.27 1.27)
				)
			)
		)
		(property "Value" "3K83R2F-GP"
			(at 0.064008 -3.993896 0)
			(unlocked yes)
			(layer "F.Fab")
			(hide yes)
			(effects
				(font
					(size 1.016 1.016)
					(thickness 0.1524)
				)
			)
		)
		(property "Device Type" "R402H16"
			(at 0.064008 -5.517896 0)
			(unlocked yes)
			(layer "F.Fab")
			(hide yes)
			(effects
				(font
					(size 1.016 1.016)
					(thickness 0.1524)
				)
			)
		)
		(duplicate_pad_numbers_are_jumpers no)
		(fp_line
			(start -0.508 -0.9398)
			(end -0.508 0.9398)
			(stroke
				(width 0.1524)
				(type default)
			)
			(layer "F.SilkS")
		)
		(fp_line
			(start 0.508 -0.9398)
			(end -0.508 -0.9398)
			(stroke
				(width 0.1524)
				(type default)
			)
			(layer "F.SilkS")
		)
		(fp_rect
			(start -0.508 0.9398)
			(end 0.508 -0.9398)
			(stroke
				(width 0)
				(type default)
			)
			(fill no)
			(layer "F.CrtYd")
		)
		(fp_rect
			(start -0.508 0.9398)
			(end 0.508 -0.9398)
			(stroke
				(width 0)
				(type default)
			)
			(fill no)
			(layer "F.Fab")
		)
		(pad "1" smd custom
			(at 0 -0.4445)
			(size 0.1397 0.1397)
			(layers "F.Cu" "F.Mask" "F.Paste")
			(net "P12V_A_PGOOD")
			(options
				(clearance outline)
				(anchor circle)
			)
			(primitives
				(gr_poly
					(pts
						(arc
							(start -0.1778 -0.2794)
							(mid -0.249642 -0.249642)
							(end -0.2794 -0.1778)
						)
						(arc
							(start -0.2794 0.1778)
							(mid -0.249642 0.249642)
							(end -0.1778 0.2794)
						)
						(arc
							(start 0.1778 0.2794)
							(mid 0.249642 0.249642)
							(end 0.2794 0.1778)
						)
						(arc
							(start 0.2794 -0.1778)
							(mid 0.249642 -0.249642)
							(end 0.1778 -0.2794)
						)
					)
					(width 0)
					(fill yes)
				)
			)
		)
		(pad "2" smd custom
			(at 0 0.4445)
			(size 0.1397 0.1397)
			(layers "F.Cu" "F.Mask" "F.Paste")
			(net "GND")
			(options
				(clearance outline)
				(anchor circle)
			)
			(primitives
				(gr_poly
					(pts
						(arc
							(start -0.1778 -0.2794)
							(mid -0.249642 -0.249642)
							(end -0.2794 -0.1778)
						)
						(arc
							(start -0.2794 0.1778)
							(mid -0.249642 0.249642)
							(end -0.1778 0.2794)
						)
						(arc
							(start 0.1778 0.2794)
							(mid 0.249642 0.249642)
							(end 0.2794 0.1778)
						)
						(arc
							(start 0.2794 -0.1778)
							(mid 0.249642 -0.249642)
							(end 0.1778 -0.2794)
						)
					)
					(width 0)
					(fill yes)
				)
			)
		)
	)
	(footprint ""
		(layer "F.Cu")
		(at 224.546922 -153.79827 -90)
		(property "Reference" "TP209"
			(at 0 0 270)
			(layer "F.SilkS")
			(hide yes)
			(effects
				(font
					(size 1.27 1.27)
				)
			)
		)
		(property "Value" "TPAD32-GP"
			(at -0.0508 -1.6764 270)
			(unlocked yes)
			(layer "F.Fab")
			(hide yes)
			(effects
				(font
					(size 1.016 1.016)
					(thickness 0.1524)
				)
			)
		)
		(property "Device Type" "TPAD32"
			(at -0.0508 -3.2004 270)
			(unlocked yes)
			(layer "F.Fab")
			(hide yes)
			(effects
				(font
					(size 1.016 1.016)
					(thickness 0.1524)
				)
			)
		)
		(duplicate_pad_numbers_are_jumpers no)
		(fp_poly
			(pts
				(arc
					(start 0 -0.4064)
					(mid 0 0.4064)
					(end 0 -0.4064)
				)
			)
			(stroke
				(width 0)
				(type default)
			)
			(fill no)
			(layer "F.CrtYd")
		)
		(fp_poly
			(pts
				(arc
					(start 0 -0.7112)
					(mid 0 0.7112)
					(end 0 -0.7112)
				)
			)
			(stroke
				(width 0)
				(type default)
			)
			(fill no)
			(layer "F.Fab")
		)
		(pad "1" smd circle
			(at 0 0 270)
			(size 0.8128 0.8128)
			(layers "F.Cu" "F.Mask" "F.Paste")
			(net "TP_COMP_A_KR_P0_TX_DP")
		)
	)
)
